# BASEBOARD_FAB2 (Tioga Pass) — schematic netlist excerpt (pin names and nets, part order shuffled) for the footprints in the layout excerpt that follows; sources: Cadence DE-HDL packaged netlist, KiCad conversion of Wiwynn_Tioga_Pass_MB.brd

J4A2  SCONN288_H44441004  SCONN  pkg PIP  page 51
  \12v\(1)  = P12V_NVDIMM_DEF
  VSS(93)  = GND
  DQ(4)  = M_E_DQ<5>
  VSS(92)  = GND
  DQ(0)  = M_E_DQ<1>
  VSS(91)  = GND
  DQS9P  = M_E_DQS_DP<9>
  DQS9N  = M_E_DQS_DN<9>
  VSS(90)  = GND
  DQ(6)  = M_E_DQ<7>
  VSS(89)  = GND
  DQ(2)  = M_E_DQ<3>
  VSS(88)  = GND
  DQ(12)  = M_E_DQ<13>
  VSS(87)  = GND
  DQ(8)  = M_E_DQ<9>
  VSS(86)  = GND
  DQS10P  = M_E_DQS_DP<10>
  DQS10N  = M_E_DQS_DN<10>
  VSS(85)  = GND
  DQ(14)  = M_E_DQ<15>
  VSS(84)  = GND
  DQ(10)  = M_E_DQ<11>
  VSS(83)  = GND
  DQ(20)  = M_E_DQ<21>
  VSS(82)  = GND
  DQ(16)  = M_E_DQ<17>
  VSS(81)  = GND
  DQS11P  = M_E_DQS_DP<11>
  DQS11N  = M_E_DQS_DN<11>
  VSS(80)  = GND
  DQ(22)  = M_E_DQ<23>
  VSS(79)  = GND
  DQ(18)  = M_E_DQ<19>
  VSS(78)  = GND
  DQ(28)  = M_E_DQ<29>
  VSS(77)  = GND
  DQ(24)  = M_E_DQ<25>
  VSS(76)  = GND
  DQS12P  = M_E_DQS_DP<12>
  DQS12N  = M_E_DQS_DN<12>
  VSS(75)  = GND
  DQ(30)  = M_E_DQ<31>
  VSS(74)  = GND
  DQ(26)  = M_E_DQ<27>
  VSS(73)  = GND
  CB(4)  = M_E_ECC<5>
  VSS(72)  = GND
  CB(0)  = M_E_ECC<1>
  VSS(71)  = GND
  DQS17P  = M_E_DQS_DP<17>
  DQS17N  = M_E_DQS_DN<17>
  VSS(70)  = GND
  CB(6)  = M_E_ECC<7>
  VSS(69)  = GND
  CB(2)  = M_E_ECC<3>
  VSS(68)  = GND
  RESET_N  = M_DEF_RST_N
  VDD(25)  = PVDDQ_DEF
  CKE(0)  = M_E_CKE<0>
  VDD(24)  = PVDDQ_DEF
  ACT_N  = M_E_ACT_N
  BG(0)  = M_E_BG<0>
  VDD(23)  = PVDDQ_DEF
  A12  = M_E_MA<12>
  A9  = M_E_MA<9>
  VDD(22)  = PVDDQ_DEF
  A8  = M_E_MA<8>
  A6  = M_E_MA<6>
  VDD(21)  = PVDDQ_DEF
  A3  = M_E_MA<3>
  A1  = M_E_MA<1>
  VDD(20)  = PVDDQ_DEF
  CK0P  = M_E_CLK_DP<0>
  CK0N  = M_E_CLK_DN<0>
  VDD(19)  = PVDDQ_DEF
  VTT(1)  = PVTT_DEF
  EVENT_N  = FM_DIMM_EVENT_COD_N
  A0  = M_E_MA<0>
  VDD(18)  = PVDDQ_DEF
  BA(0)  = M_E_BA<0>
  A16_RAS_N  = M_E_MA<16>
  VDD(17)  = PVDDQ_DEF
  S0_N  = M_E_CS_N<0>
  VDD(16)  = PVDDQ_DEF
  A15_CAS_N  = M_E_MA<15>
  ODT(0)  = M_E_ODT<0>
  VDD(15)  = PVDDQ_DEF
  S1_N  = M_E_CS_N<1>
  VDD(14)  = PVDDQ_DEF
  ODT(1)  = M_E_ODT<1>
  VDD(13)  = PVDDQ_DEF
  S2_N_C(0)  = M_E_CS_N<2>
  VSS(67)  = GND
  DQ(36)  = M_E_DQ<37>
  VSS(66)  = GND
  DQ(32)  = M_E_DQ<33>
  VSS(65)  = GND
  DQS13P  = M_E_DQS_DP<13>
  DQS13N  = M_E_DQS_DN<13>
  VSS(64)  = GND
  DQ(38)  = M_E_DQ<39>
  VSS(63)  = GND
  DQ(34)  = M_E_DQ<35>
  VSS(62)  = GND
  DQ(44)  = M_E_DQ<45>
  VSS(61)  = GND
  DQ(40)  = M_E_DQ<41>
  VSS(60)  = GND
  DQS14P  = M_E_DQS_DP<14>
  DQS14N  = M_E_DQS_DN<14>
  VSS(59)  = GND
  DQ(46)  = M_E_DQ<47>
  VSS(58)  = GND
  DQ(42)  = M_E_DQ<43>
  VSS(57)  = GND
  DQ(52)  = M_E_DQ<53>
  VSS(56)  = GND
  DQ(48)  = M_E_DQ<49>
  VSS(55)  = GND
  DQS15P  = M_E_DQS_DP<15>
  DQS15N  = M_E_DQS_DN<15>
  VSS(54)  = GND
  DQ(54)  = M_E_DQ<55>
  VSS(53)  = GND
  DQ(50)  = M_E_DQ<51>
  VSS(52)  = GND
  DQ(60)  = M_E_DQ<61>
  VSS(51)  = GND
  DQ(56)  = M_E_DQ<57>
  VSS(50)  = GND
  DQS16P  = M_E_DQS_DP<16>
  DQS16N  = M_E_DQS_DN<16>
  VSS(49)  = GND
  DQ(62)  = M_E_DQ<63>
  VSS(48)  = GND
  DQ(58)  = M_E_DQ<59>
  VSS(47)  = GND
  SA(0)  = GND
  SA(1)  = PVPP_DEF
  SCL  = SMB_DDR_DEF_VPP_SCL
  VPP(4)  = PVPP_DEF
  VPP(3)  = PVPP_DEF
  RFU(2)  = TP_CH_E_DIMM_E0_RFU_2
  \12v\(0)  = P12V_NVDIMM_DEF
  VREFCA  = M_E_VREF
  VSS(46)  = GND
  DQ(5)  = M_E_DQ<4>
  VSS(45)  = GND
  DQ(1)  = M_E_DQ<0>
  VSS(44)  = GND
  DQS0N  = M_E_DQS_DN<0>
  DQS0P  = M_E_DQS_DP<0>
  VSS(43)  = GND
  DQ(7)  = M_E_DQ<6>
  VSS(42)  = GND
  DQ(3)  = M_E_DQ<2>
  VSS(41)  = GND
  DQ(13)  = M_E_DQ<12>
  VSS(40)  = GND
  DQ(9)  = M_E_DQ<8>
  VSS(39)  = GND
  DQS1N  = M_E_DQS_DN<1>
  DQS1P  = M_E_DQS_DP<1>
  VSS(38)  = GND
  DQ(15)  = M_E_DQ<14>
  VSS(37)  = GND
  DQ(11)  = M_E_DQ<10>
  VSS(36)  = GND
  DQ(21)  = M_E_DQ<20>
  VSS(35)  = GND
  DQ(17)  = M_E_DQ<16>
  VSS(34)  = GND
  DQS2N  = M_E_DQS_DN<2>
  DQS2P  = M_E_DQS_DP<2>
  VSS(33)  = GND
  DQ(23)  = M_E_DQ<22>
  VSS(32)  = GND
  DQ(19)  = M_E_DQ<18>
  VSS(31)  = GND
  DQ(29)  = M_E_DQ<28>
  VSS(30)  = GND
  DQ(25)  = M_E_DQ<24>
  VSS(29)  = GND
  DQS3N  = M_E_DQS_DN<3>
  DQS3P  = M_E_DQS_DP<3>
  VSS(28)  = GND
  DQ(31)  = M_E_DQ<30>
  VSS(27)  = GND
  DQ(27)  = M_E_DQ<26>
  VSS(26)  = GND
  CB(5)  = M_E_ECC<4>
  VSS(25)  = GND
  CB(1)  = M_E_ECC<0>
  VSS(24)  = GND
  DQS8N  = M_E_DQS_DN<8>
  DQS8P  = M_E_DQS_DP<8>
  VSS(23)  = GND
  CB(7)  = M_E_ECC<6>
  VSS(22)  = GND
  CB(3)  = M_E_ECC<2>
  VSS(21)  = GND
  CKE(1)  = M_E_CKE<1>
  VDD(12)  = PVDDQ_DEF
  RFU(0)  = TP_CH_E_DIMM_E0_RFU_0
  VDD(11)  = PVDDQ_DEF
  BG(1)  = M_E_BG<1>
  ALERT_N  = M_E_ALERT_N
  VDD(10)  = PVDDQ_DEF
  A11  = M_E_MA<11>
  A7  = M_E_MA<7>
  VDD(9)  = PVDDQ_DEF
  A5  = M_E_MA<5>
  A4  = M_E_MA<4>
  VDD(8)  = PVDDQ_DEF
  A2  = M_E_MA<2>
  VDD(7)  = PVDDQ_DEF
  CK1P  = M_E_CLK_DP<1>
  CK1N  = M_E_CLK_DN<1>
  VDD(6)  = PVDDQ_DEF
  VTT(0)  = PVTT_DEF
  PAR  = M_E_PAR
  VDD(5)  = PVDDQ_DEF
  BA(1)  = M_E_BA<1>
  A10  = M_E_MA<10>
  VDD(4)  = PVDDQ_DEF
  RFU(1)  = TP_CH_E_DIMM_E0_RFU_1
  A14_WE_N  = M_E_MA<14>
  VDD(3)  = PVDDQ_DEF
  SAVE_N_NC  = FM_ADR_COMPLETE_DEF_N
  VDD(2)  = PVDDQ_DEF
  A13  = M_E_MA<13>
  VDD(1)  = PVDDQ_DEF
  A17  = M_E_MA<17>
  C(2)  = M_E_C<2>
  VDD(0)  = PVDDQ_DEF
  S3_N_C(1)  = M_E_CS_N<3>
  SA(2)  = GND
  VSS(20)  = GND
  DQ(37)  = M_E_DQ<36>
  VSS(19)  = GND
  DQ(33)  = M_E_DQ<32>
  VSS(18)  = GND
  DQS4N  = M_E_DQS_DN<4>
  DQS4P  = M_E_DQS_DP<4>
  VSS(17)  = GND
  DQ(39)  = M_E_DQ<38>
  VSS(16)  = GND
  DQ(35)  = M_E_DQ<34>
  VSS(15)  = GND
  DQ(45)  = M_E_DQ<44>
  VSS(14)  = GND
  DQ(41)  = M_E_DQ<40>
  VSS(13)  = GND
  DQS5N  = M_E_DQS_DN<5>
  DQS5P  = M_E_DQS_DP<5>
  VSS(12)  = GND
  DQ(47)  = M_E_DQ<46>
  VSS(11)  = GND
  DQ(43)  = M_E_DQ<42>
  VSS(10)  = GND
  DQ(53)  = M_E_DQ<52>
  VSS(9)  = GND
  DQ(49)  = M_E_DQ<48>
  VSS(8)  = GND
  DQS6N  = M_E_DQS_DN<6>
  DQS6P  = M_E_DQS_DP<6>
  VSS(7)  = GND
  DQ(55)  = M_E_DQ<54>
  VSS(6)  = GND
  DQ(51)  = M_E_DQ<50>
  VSS(5)  = GND
  DQ(61)  = M_E_DQ<60>
  VSS(4)  = GND
  DQ(57)  = M_E_DQ<56>
  VSS(3)  = GND
  DQS7N  = M_E_DQS_DN<7>
  DQS7P  = M_E_DQS_DP<7>
  VSS(2)  = GND
  DQ(63)  = M_E_DQ<62>
  VSS(1)  = GND
  DQ(59)  = M_E_DQ<58>
  VSS(0)  = GND
  VDDSPD  = PVPP_DEF
  SDA  = SMB_DDR_DEF_VPP_SDA
  VPP(1)  = PVPP_DEF
  VPP(0)  = PVPP_DEF
  VPP(2)  = PVPP_DEF

(kicad_pcb
	(version 20260206)
	(generator "pcbnew")
	(generator_version "10.0")
	(general
		(thickness 1.6)
		(legacy_teardrops no)
	)
	(paper "A4")
	(title_block
		(title "Wiwynn_Tioga_Pass_MB.brd")
		(comment 1 "Tioga Pass / footprint 2096 of 4770 (J4A2), pads 1-51 of 291")
	)
	(layers
		(0 "F.Cu" signal "TOP")
		(4 "In1.Cu" signal "L2GND")
		(6 "In2.Cu" signal "L3")
		(8 "In3.Cu" signal "L4GND")
		(10 "In4.Cu" signal "L5")
		(12 "In5.Cu" signal "L6GND")
		(14 "In6.Cu" signal "L7VCC")
		(16 "In7.Cu" signal "L8VCC")
		(18 "In8.Cu" signal "L9GND")
		(20 "In9.Cu" signal "L10")
		(22 "In10.Cu" signal "L11GND")
		(24 "In11.Cu" signal "L12")
		(26 "In12.Cu" signal "L13GND")
		(2 "B.Cu" signal "BOTTOM")
		(9 "F.Adhes" user "F.Adhesive")
		(11 "B.Adhes" user "B.Adhesive")
		(13 "F.Paste" user "Package Geometry/Pastemask Top")
		(15 "B.Paste" user "Package Geometry/Pastemask Bottom")
		(5 "F.SilkS" user "Ref Des/Silkscreen Top")
		(7 "B.SilkS" user "Ref Des/Silkscreen Bottom")
		(1 "F.Mask" user "Board Geometry/Soldermask Top")
		(3 "B.Mask" user "Board Geometry/Soldermask Bottom")
		(17 "Dwgs.User" user "User.Drawings")
		(19 "Cmts.User" user "User.Comments")
		(21 "Eco1.User" user "User.Eco1")
		(23 "Eco2.User" user "User.Eco2")
		(25 "Edge.Cuts" user "Board Geometry/Outline")
		(27 "Margin" user)
		(31 "F.CrtYd" user "Package Geometry/Place Bound Top")
		(29 "B.CrtYd" user "Package Geometry/Place Bound Bottom")
		(35 "F.Fab" user "Ref Des/Assembly Top")
		(33 "B.Fab" user "Ref Des/Assembly Bottom")
	)
	(footprint ""
		(layer "F.Cu")
		(at 194.700398 -142.6718 90)
		(property "Reference" "J4A2"
			(at -2.369312 42.66311 0)
			(unlocked yes)
			(layer "F.SilkS")
			(effects
				(font
					(size 0.7874 0.5842)
					(thickness 0.1524)
				)
				(justify left)
			)
		)
		(property "Value" ""
			(at 0 0 90)
			(layer "F.Fab")
			(effects
				(font
					(size 1.27 1.27)
				)
			)
		)
		(duplicate_pad_numbers_are_jumpers no)
		(pad "" thru_hole circle
			(at 2.29997 -5.649976 90)
			(size 2.8194 2.8194)
			(drill 2.4384)
			(layers "*.Cu" "*.Mask")
			(remove_unused_layers no)
			(clearance 0.127)
			(thermal_gap 0.127)
		)
		(pad "" thru_hole oval
			(at 2.29997 68.90004 90)
			(size 2.8194 1.5748)
			(drill oval 2.4384 1.1938)
			(layers "*.Cu" "*.Mask")
			(remove_unused_layers no)
			(clearance 0.127)
			(thermal_gap 0.127)
		)
		(pad "" thru_hole circle
			(at 2.29997 132.299964 90)
			(size 2.8194 2.8194)
			(drill 2.4384)
			(layers "*.Cu" "*.Mask")
			(remove_unused_layers no)
			(clearance 0.127)
			(thermal_gap 0.127)
		)
		(pad "1" smd rect
			(at 0 0 90)
			(size 1.8034 0.508)
			(layers "F.Cu" "F.Mask" "F.Paste")
			(net "P12V_NVDIMM_DEF")
		)
		(pad "2" smd rect
			(at 0 0.849884 90)
			(size 1.8034 0.508)
			(layers "F.Cu" "F.Mask" "F.Paste")
			(net "GND")
		)
		(pad "3" smd rect
			(at 0 1.700022 90)
			(size 1.8034 0.508)
			(layers "F.Cu" "F.Mask" "F.Paste")
			(net "M_E_DQ<5>")
		)
		(pad "4" smd rect
			(at 0 2.549906 90)
			(size 1.8034 0.508)
			(layers "F.Cu" "F.Mask" "F.Paste")
			(net "GND")
		)
		(pad "5" smd rect
			(at 0 3.400044 90)
			(size 1.8034 0.508)
			(layers "F.Cu" "F.Mask" "F.Paste")
			(net "M_E_DQ<1>")
		)
		(pad "6" smd rect
			(at 0 4.249928 90)
			(size 1.8034 0.508)
			(layers "F.Cu" "F.Mask" "F.Paste")
			(net "GND")
		)
		(pad "7" smd rect
			(at 0 5.100066 90)
			(size 1.8034 0.508)
			(layers "F.Cu" "F.Mask" "F.Paste")
			(net "M_E_DQS_DP<9>")
		)
		(pad "8" smd rect
			(at 0 5.94995 90)
			(size 1.8034 0.508)
			(layers "F.Cu" "F.Mask" "F.Paste")
			(net "M_E_DQS_DN<9>")
		)
		(pad "9" smd rect
			(at 0 6.800088 90)
			(size 1.8034 0.508)
			(layers "F.Cu" "F.Mask" "F.Paste")
			(net "GND")
		)
		(pad "10" smd rect
			(at 0 7.649972 90)
			(size 1.8034 0.508)
			(layers "F.Cu" "F.Mask" "F.Paste")
			(net "M_E_DQ<7>")
		)
		(pad "11" smd rect
			(at 0 8.50011 90)
			(size 1.8034 0.508)
			(layers "F.Cu" "F.Mask" "F.Paste")
			(net "GND")
		)
		(pad "12" smd rect
			(at 0 9.349994 90)
			(size 1.8034 0.508)
			(layers "F.Cu" "F.Mask" "F.Paste")
			(net "M_E_DQ<3>")
		)
		(pad "13" smd rect
			(at 0 10.199878 90)
			(size 1.8034 0.508)
			(layers "F.Cu" "F.Mask" "F.Paste")
			(net "GND")
		)
		(pad "14" smd rect
			(at 0 11.050016 90)
			(size 1.8034 0.508)
			(layers "F.Cu" "F.Mask" "F.Paste")
			(net "M_E_DQ<13>")
		)
		(pad "15" smd rect
			(at 0 11.8999 90)
			(size 1.8034 0.508)
			(layers "F.Cu" "F.Mask" "F.Paste")
			(net "GND")
		)
		(pad "16" smd rect
			(at 0 12.750038 90)
			(size 1.8034 0.508)
			(layers "F.Cu" "F.Mask" "F.Paste")
			(net "M_E_DQ<9>")
		)
		(pad "17" smd rect
			(at 0 13.599922 90)
			(size 1.8034 0.508)
			(layers "F.Cu" "F.Mask" "F.Paste")
			(net "GND")
		)
		(pad "18" smd rect
			(at 0 14.45006 90)
			(size 1.8034 0.508)
			(layers "F.Cu" "F.Mask" "F.Paste")
			(net "M_E_DQS_DP<10>")
		)
		(pad "19" smd rect
			(at 0 15.299944 90)
			(size 1.8034 0.508)
			(layers "F.Cu" "F.Mask" "F.Paste")
			(net "M_E_DQS_DN<10>")
		)
		(pad "20" smd rect
			(at 0 16.150082 90)
			(size 1.8034 0.508)
			(layers "F.Cu" "F.Mask" "F.Paste")
			(net "GND")
		)
		(pad "21" smd rect
			(at 0 16.999966 90)
			(size 1.8034 0.508)
			(layers "F.Cu" "F.Mask" "F.Paste")
			(net "M_E_DQ<15>")
		)
		(pad "22" smd rect
			(at 0 17.850104 90)
			(size 1.8034 0.508)
			(layers "F.Cu" "F.Mask" "F.Paste")
			(net "GND")
		)
		(pad "23" smd rect
			(at 0 18.699988 90)
			(size 1.8034 0.508)
			(layers "F.Cu" "F.Mask" "F.Paste")
			(net "M_E_DQ<11>")
		)
		(pad "24" smd rect
			(at 0 19.550126 90)
			(size 1.8034 0.508)
			(layers "F.Cu" "F.Mask" "F.Paste")
			(net "GND")
		)
		(pad "25" smd rect
			(at 0 20.40001 90)
			(size 1.8034 0.508)
			(layers "F.Cu" "F.Mask" "F.Paste")
			(net "M_E_DQ<21>")
		)
		(pad "26" smd rect
			(at 0 21.249894 90)
			(size 1.8034 0.508)
			(layers "F.Cu" "F.Mask" "F.Paste")
			(net "GND")
		)
		(pad "27" smd rect
			(at 0 22.100032 90)
			(size 1.8034 0.508)
			(layers "F.Cu" "F.Mask" "F.Paste")
			(net "M_E_DQ<17>")
		)
		(pad "28" smd rect
			(at 0 22.949916 90)
			(size 1.8034 0.508)
			(layers "F.Cu" "F.Mask" "F.Paste")
			(net "GND")
		)
		(pad "29" smd rect
			(at 0 23.800054 90)
			(size 1.8034 0.508)
			(layers "F.Cu" "F.Mask" "F.Paste")
			(net "M_E_DQS_DP<11>")
		)
		(pad "30" smd rect
			(at 0 24.649938 90)
			(size 1.8034 0.508)
			(layers "F.Cu" "F.Mask" "F.Paste")
			(net "M_E_DQS_DN<11>")
		)
		(pad "31" smd rect
			(at 0 25.500076 90)
			(size 1.8034 0.508)
			(layers "F.Cu" "F.Mask" "F.Paste")
			(net "GND")
		)
		(pad "32" smd rect
			(at 0 26.34996 90)
			(size 1.8034 0.508)
			(layers "F.Cu" "F.Mask" "F.Paste")
			(net "M_E_DQ<23>")
		)
		(pad "33" smd rect
			(at 0 27.200098 90)
			(size 1.8034 0.508)
			(layers "F.Cu" "F.Mask" "F.Paste")
			(net "GND")
		)
		(pad "34" smd rect
			(at 0 28.049982 90)
			(size 1.8034 0.508)
			(layers "F.Cu" "F.Mask" "F.Paste")
			(net "M_E_DQ<19>")
		)
		(pad "35" smd rect
			(at 0 28.90012 90)
			(size 1.8034 0.508)
			(layers "F.Cu" "F.Mask" "F.Paste")
			(net "GND")
		)
		(pad "36" smd rect
			(at 0 29.750004 90)
			(size 1.8034 0.508)
			(layers "F.Cu" "F.Mask" "F.Paste")
			(net "M_E_DQ<29>")
		)
		(pad "37" smd rect
			(at 0 30.599888 90)
			(size 1.8034 0.508)
			(layers "F.Cu" "F.Mask" "F.Paste")
			(net "GND")
		)
		(pad "38" smd rect
			(at 0 31.450026 90)
			(size 1.8034 0.508)
			(layers "F.Cu" "F.Mask" "F.Paste")
			(net "M_E_DQ<25>")
		)
		(pad "39" smd rect
			(at 0 32.29991 90)
			(size 1.8034 0.508)
			(layers "F.Cu" "F.Mask" "F.Paste")
			(net "GND")
		)
		(pad "40" smd rect
			(at 0 33.150048 90)
			(size 1.8034 0.508)
			(layers "F.Cu" "F.Mask" "F.Paste")
			(net "M_E_DQS_DP<12>")
		)
		(pad "41" smd rect
			(at 0 33.999932 90)
			(size 1.8034 0.508)
			(layers "F.Cu" "F.Mask" "F.Paste")
			(net "M_E_DQS_DN<12>")
		)
		(pad "42" smd rect
			(at 0 34.85007 90)
			(size 1.8034 0.508)
			(layers "F.Cu" "F.Mask" "F.Paste")
			(net "GND")
		)
		(pad "43" smd rect
			(at 0 35.699954 90)
			(size 1.8034 0.508)
			(layers "F.Cu" "F.Mask" "F.Paste")
			(net "M_E_DQ<31>")
		)
		(pad "44" smd rect
			(at 0 36.550092 90)
			(size 1.8034 0.508)
			(layers "F.Cu" "F.Mask" "F.Paste")
			(net "GND")
		)
		(pad "45" smd rect
			(at 0 37.399976 90)
			(size 1.8034 0.508)
			(layers "F.Cu" "F.Mask" "F.Paste")
			(net "M_E_DQ<27>")
		)
		(pad "46" smd rect
			(at 0 38.250114 90)
			(size 1.8034 0.508)
			(layers "F.Cu" "F.Mask" "F.Paste")
			(net "GND")
		)
		(pad "47" smd rect
			(at 0 39.099998 90)
			(size 1.8034 0.508)
			(layers "F.Cu" "F.Mask" "F.Paste")
			(net "M_E_ECC<5>")
		)
		(pad "48" smd rect
			(at 0 39.949882 90)
			(size 1.8034 0.508)
			(layers "F.Cu" "F.Mask" "F.Paste")
			(net "GND")
		)
	)
)
